# T6G (Grand Teton) — schematic netlist excerpt (pin names and nets, part order shuffled) for the footprints in the layout excerpt that follows; sources: Cadence DE-HDL packaged netlist, KiCad conversion of 04192023_DAF0TMB3IC0_F0TG_MB_C_brd_V02_OCP.brd

C2389  Q_CAP  22UF 4V 20% X6S  pkg C0402  page 73 : A = PVDDCR_CPU1_P1 ; B = GND
C2142  Q_CAP  22UF 4V 20% X6S  pkg C0402  page 68 : A = PVDD11_S3_P0 ; B = GND

(kicad_pcb
	(version 20260206)
	(generator "pcbnew")
	(generator_version "10.0")
	(general
		(thickness 1.6)
		(legacy_teardrops no)
	)
	(paper "A4")
	(title_block
		(title "04192023_DAF0TMB3IC0_F0TG_MB_C_brd_V02_OCP.brd")
		(comment 1 "Grand Teton / footprints 7996-7997 of 8354")
	)
	(layers
		(0 "F.Cu" signal "TOP")
		(4 "In1.Cu" signal "GND")
		(6 "In2.Cu" signal "IN1")
		(8 "In3.Cu" signal "GND1")
		(10 "In4.Cu" signal "IN2")
		(12 "In5.Cu" signal "GND2")
		(14 "In6.Cu" signal "IN3")
		(16 "In7.Cu" signal "GND3")
		(18 "In8.Cu" signal "VCC")
		(20 "In9.Cu" signal "VCC1")
		(22 "In10.Cu" signal "GND4")
		(24 "In11.Cu" signal "IN4")
		(26 "In12.Cu" signal "GND5")
		(28 "In13.Cu" signal "IN5")
		(30 "In14.Cu" signal "GND6")
		(32 "In15.Cu" signal "IN6")
		(34 "In16.Cu" signal "GND7")
		(2 "B.Cu" signal "BOTTOM")
		(9 "F.Adhes" user "F.Adhesive")
		(11 "B.Adhes" user "B.Adhesive")
		(13 "F.Paste" user "Package Geometry/Pastemask Top")
		(15 "B.Paste" user "Package Geometry/Pastemask Bottom")
		(5 "F.SilkS" user "Ref Des/Silkscreen Top")
		(7 "B.SilkS" user "Ref Des/Silkscreen Bottom")
		(1 "F.Mask" user "Board Geometry/Soldermask Top")
		(3 "B.Mask" user "Board Geometry/Soldermask Bottom")
		(17 "Dwgs.User" user "User.Drawings")
		(19 "Cmts.User" user "User.Comments")
		(21 "Eco1.User" user "User.Eco1")
		(23 "Eco2.User" user "User.Eco2")
		(25 "Edge.Cuts" user "Board Geometry/Outline")
		(27 "Margin" user)
		(31 "F.CrtYd" user "Package Geometry/Place Bound Top")
		(29 "B.CrtYd" user "Package Geometry/Place Bound Bottom")
		(35 "F.Fab" user "Ref Des/Assembly Top")
		(33 "B.Fab" user "Ref Des/Assembly Bottom")
	)
	(footprint ""
		(layer "B.Cu")
		(at 367.614454 -266.00531)
		(property "Reference" "C2142"
			(at 0 0 0)
			(layer "B.SilkS")
			(hide yes)
			(effects
				(font
					(size 1.27 1.27)
				)
				(justify mirror)
			)
		)
		(property "Value" ""
			(at 0 0 0)
			(layer "B.Fab")
			(effects
				(font
					(size 1.27 1.27)
				)
				(justify mirror)
			)
		)
		(duplicate_pad_numbers_are_jumpers no)
		(fp_line
			(start -0.7874 -0.4064)
			(end -0.7874 0.4064)
			(stroke
				(width 0.1524)
				(type default)
			)
			(layer "B.SilkS")
		)
		(fp_line
			(start -0.7874 0.4064)
			(end 0.7874 0.4064)
			(stroke
				(width 0.1524)
				(type default)
			)
			(layer "B.SilkS")
		)
		(fp_line
			(start 0.7874 -0.4064)
			(end -0.7874 -0.4064)
			(stroke
				(width 0.1524)
				(type default)
			)
			(layer "B.SilkS")
		)
		(fp_line
			(start 0.7874 0.4064)
			(end 0.7874 -0.4064)
			(stroke
				(width 0.1524)
				(type default)
			)
			(layer "B.SilkS")
		)
		(fp_line
			(start -0.67945 -0.3048)
			(end -0.67945 0.3048)
			(stroke
				(width 0.1)
				(type default)
			)
			(layer "B.Fab")
		)
		(fp_line
			(start -0.67945 0.3048)
			(end -0.120396 0.3048)
			(stroke
				(width 0.1)
				(type default)
			)
			(layer "B.Fab")
		)
		(fp_line
			(start -0.12065 -0.3048)
			(end -0.67945 -0.3048)
			(stroke
				(width 0.1)
				(type default)
			)
			(layer "B.Fab")
		)
		(fp_line
			(start -0.12065 -0.2794)
			(end -0.12065 -0.3048)
			(stroke
				(width 0.1)
				(type default)
			)
			(layer "B.Fab")
		)
		(fp_line
			(start -0.120396 0.2794)
			(end 0.12065 0.2794)
			(stroke
				(width 0.1)
				(type default)
			)
			(layer "B.Fab")
		)
		(fp_line
			(start -0.120396 0.3048)
			(end -0.120396 0.2794)
			(stroke
				(width 0.1)
				(type default)
			)
			(layer "B.Fab")
		)
		(fp_line
			(start 0.12065 -0.305054)
			(end 0.12065 -0.2794)
			(stroke
				(width 0.1)
				(type default)
			)
			(layer "B.Fab")
		)
		(fp_line
			(start 0.12065 -0.2794)
			(end -0.12065 -0.2794)
			(stroke
				(width 0.1)
				(type default)
			)
			(layer "B.Fab")
		)
		(fp_line
			(start 0.12065 0.2794)
			(end 0.12065 0.3048)
			(stroke
				(width 0.1)
				(type default)
			)
			(layer "B.Fab")
		)
		(fp_line
			(start 0.12065 0.3048)
			(end 0.67945 0.3048)
			(stroke
				(width 0.1)
				(type default)
			)
			(layer "B.Fab")
		)
		(fp_line
			(start 0.67945 -0.305054)
			(end 0.12065 -0.305054)
			(stroke
				(width 0.1)
				(type default)
			)
			(layer "B.Fab")
		)
		(fp_line
			(start 0.67945 0.3048)
			(end 0.67945 -0.305054)
			(stroke
				(width 0.1)
				(type default)
			)
			(layer "B.Fab")
		)
		(pad "1" smd circle
			(at 0.40005 0 180)
			(size 0 0)
			(layers "B.Cu" "B.Mask" "B.Paste")
			(net "PVDD11_S3_P0")
		)
		(pad "2" smd circle
			(at -0.40005 0 180)
			(size 0 0)
			(layers "B.Cu" "B.Mask" "B.Paste")
			(net "GND")
		)
	)
	(footprint ""
		(layer "B.Cu")
		(at 101.668834 -272.284952 180)
		(property "Reference" "C2389"
			(at 0 0 0)
			(layer "B.SilkS")
			(hide yes)
			(effects
				(font
					(size 1.27 1.27)
				)
				(justify mirror)
			)
		)
		(property "Value" ""
			(at 0 0 0)
			(layer "B.Fab")
			(effects
				(font
					(size 1.27 1.27)
				)
				(justify mirror)
			)
		)
		(duplicate_pad_numbers_are_jumpers no)
		(fp_line
			(start 0.7874 0.4064)
			(end 0.7874 -0.4064)
			(stroke
				(width 0.1524)
				(type default)
			)
			(layer "B.SilkS")
		)
		(fp_line
			(start 0.7874 -0.4064)
			(end -0.7874 -0.4064)
			(stroke
				(width 0.1524)
				(type default)
			)
			(layer "B.SilkS")
		)
		(fp_line
			(start -0.7874 0.4064)
			(end 0.7874 0.4064)
			(stroke
				(width 0.1524)
				(type default)
			)
			(layer "B.SilkS")
		)
		(fp_line
			(start -0.7874 -0.4064)
			(end -0.7874 0.4064)
			(stroke
				(width 0.1524)
				(type default)
			)
			(layer "B.SilkS")
		)
		(fp_line
			(start 0.67945 0.3048)
			(end 0.67945 -0.305054)
			(stroke
				(width 0.1)
				(type default)
			)
			(layer "B.Fab")
		)
		(fp_line
			(start 0.67945 -0.305054)
			(end 0.12065 -0.305054)
			(stroke
				(width 0.1)
				(type default)
			)
			(layer "B.Fab")
		)
		(fp_line
			(start 0.12065 0.3048)
			(end 0.67945 0.3048)
			(stroke
				(width 0.1)
				(type default)
			)
			(layer "B.Fab")
		)
		(fp_line
			(start 0.12065 0.2794)
			(end 0.12065 0.3048)
			(stroke
				(width 0.1)
				(type default)
			)
			(layer "B.Fab")
		)
		(fp_line
			(start 0.12065 -0.2794)
			(end -0.12065 -0.2794)
			(stroke
				(width 0.1)
				(type default)
			)
			(layer "B.Fab")
		)
		(fp_line
			(start 0.12065 -0.305054)
			(end 0.12065 -0.2794)
			(stroke
				(width 0.1)
				(type default)
			)
			(layer "B.Fab")
		)
		(fp_line
			(start -0.120396 0.3048)
			(end -0.120396 0.2794)
			(stroke
				(width 0.1)
				(type default)
			)
			(layer "B.Fab")
		)
		(fp_line
			(start -0.120396 0.2794)
			(end 0.12065 0.2794)
			(stroke
				(width 0.1)
				(type default)
			)
			(layer "B.Fab")
		)
		(fp_line
			(start -0.12065 -0.2794)
			(end -0.12065 -0.3048)
			(stroke
				(width 0.1)
				(type default)
			)
			(layer "B.Fab")
		)
		(fp_line
			(start -0.12065 -0.3048)
			(end -0.67945 -0.3048)
			(stroke
				(width 0.1)
				(type default)
			)
			(layer "B.Fab")
		)
		(fp_line
			(start -0.67945 0.3048)
			(end -0.120396 0.3048)
			(stroke
				(width 0.1)
				(type default)
			)
			(layer "B.Fab")
		)
		(fp_line
			(start -0.67945 -0.3048)
			(end -0.67945 0.3048)
			(stroke
				(width 0.1)
				(type default)
			)
			(layer "B.Fab")
		)
		(pad "1" smd circle
			(at 0.40005 0)
			(size 0 0)
			(layers "B.Cu" "B.Mask" "B.Paste")
			(net "PVDDCR_CPU1_P1")
		)
		(pad "2" smd circle
			(at -0.40005 0)
			(size 0 0)
			(layers "B.Cu" "B.Mask" "B.Paste")
			(net "GND")
		)
	)
)
